FILE_TYPE=LIBRARY_PARTS;
primitive 'MOSFET_N','MOSFET_N_TO252C','MOSFET_N_SMLF','MOSFET_N_SM';
  pin
    'GATE':
      PIN_NUMBER='(1)';
      PINUSE='UNSPEC';
      NO_LOAD_CHECK='BOTH';
      NO_IO_CHECK='BOTH';
      ALLOW_CONNECT='TRUE';
    'SRC':
      PIN_NUMBER='(3)';
      PINUSE='UNSPEC';
      NO_LOAD_CHECK='BOTH';
      NO_IO_CHECK='BOTH';
      ALLOW_CONNECT='TRUE';
    'DRN':
      PIN_NUMBER='(2)';
      PINUSE='UNSPEC';
      NO_LOAD_CHECK='BOTH';
      NO_IO_CHECK='BOTH';
      ALLOW_CONNECT='TRUE';
  end_pin;
  body
    PART_NAME='MOSFET_N';
    PHYS_DES_PREFIX='Q';
  end_body;
end_primitive;
primitive 'MOSFET_N_SOT323','MOSFET_N_SOT23';
  pin
    'GATE':
      PIN_NUMBER='(1)';
      PINUSE='UNSPEC';
      NO_LOAD_CHECK='BOTH';
      NO_IO_CHECK='BOTH';
      ALLOW_CONNECT='TRUE';
    'SRC':
      PIN_NUMBER='(2)';
      PINUSE='UNSPEC';
      NO_LOAD_CHECK='BOTH';
      NO_IO_CHECK='BOTH';
      ALLOW_CONNECT='TRUE';
    'DRN':
      PIN_NUMBER='(3)';
      PINUSE='UNSPEC';
      NO_LOAD_CHECK='BOTH';
      NO_IO_CHECK='BOTH';
      ALLOW_CONNECT='TRUE';
  end_pin;
  body
    PART_NAME='MOSFET_N';
    PHYS_DES_PREFIX='Q';
  end_body;
  end_primitive;
  primitive 'MOSFET_N_TO252';
    pin
      'GATE':
        PIN_NUMBER='(2)';
        PINUSE='UNSPEC';
        NO_LOAD_CHECK='BOTH';
        NO_IO_CHECK='BOTH';
        ALLOW_CONNECT='TRUE';
      'SRC':
        PIN_NUMBER='(1)';
        PINUSE='UNSPEC';
        NO_LOAD_CHECK='BOTH';
        NO_IO_CHECK='BOTH';
        ALLOW_CONNECT='TRUE';
      'DRN':
        PIN_NUMBER='(3)';
        PINUSE='UNSPEC';
        NO_LOAD_CHECK='BOTH';
        NO_IO_CHECK='BOTH';
        ALLOW_CONNECT='TRUE';
    end_pin;
    body
      PART_NAME='MOSFET_N';
      PHYS_DES_PREFIX='Q';
  end_body;
end_primitive;
  primitive 'MOSFET_N_TO252AA';
    pin
      'GATE':
        PIN_NUMBER='(1)';
        PINUSE='UNSPEC';
        NO_LOAD_CHECK='BOTH';
        NO_IO_CHECK='BOTH';
        ALLOW_CONNECT='TRUE';
      'SRC':
        PIN_NUMBER='(3)';
        PINUSE='UNSPEC';
        NO_LOAD_CHECK='BOTH';
        NO_IO_CHECK='BOTH';
        ALLOW_CONNECT='TRUE';
      'DRN':
        PIN_NUMBER='(4)';
        PINUSE='UNSPEC';
        NO_LOAD_CHECK='BOTH';
        NO_IO_CHECK='BOTH';
        ALLOW_CONNECT='TRUE';
    end_pin;
    body
      PART_NAME='MOSFET_N';
      PHYS_DES_PREFIX='Q';
  end_body;
end_primitive;
  primitive 'MOSFET_N_LCC3';
    pin
      'GATE':
        PIN_NUMBER='(4)';
        PINUSE='UNSPEC';
        NO_LOAD_CHECK='BOTH';
        NO_IO_CHECK='BOTH';
        ALLOW_CONNECT='TRUE';
      'SRC':
        PIN_NUMBER='(1)';
        PINUSE='UNSPEC';
        NO_LOAD_CHECK='BOTH';
        NO_IO_CHECK='BOTH';
        ALLOW_CONNECT='TRUE';
      'DRN':
        PIN_NUMBER='(5)';
        PINUSE='UNSPEC';
        NO_LOAD_CHECK='BOTH';
        NO_IO_CHECK='BOTH';
        ALLOW_CONNECT='TRUE';
    end_pin;
    body
      PART_NAME='MOSFET_N';
      PHYS_DES_PREFIX='EU';
  end_body;
end_primitive;


END.
